(kicad_pcb
	(version 20241229)
	(generator "pcbnew")
	(generator_version "9.0")
	(general
		(thickness 1.711)
		(legacy_teardrops no)
	)
	(paper "A4")
	(title_block
		(title "Antmicro Baseboard for Jetson AGX Thor")
		(date "2026-02-18")
		(rev "1.1.0")
		(company "Antmicro Ltd")
		(comment 1 "www.antmicro.com")
		(comment 9 "footprints 486-487 of 1170")
	)
	(layers
		(0 "F.Cu" signal)
		(4 "In1.Cu" signal)
		(6 "In2.Cu" signal)
		(8 "In3.Cu" signal)
		(10 "In4.Cu" jumper)
		(12 "In5.Cu" signal)
		(14 "In6.Cu" signal)
		(16 "In7.Cu" signal)
		(18 "In8.Cu" signal)
		(2 "B.Cu" signal)
		(9 "F.Adhes" user "F.Adhesive")
		(11 "B.Adhes" user "B.Adhesive")
		(13 "F.Paste" user)
		(15 "B.Paste" user)
		(5 "F.SilkS" user "F.Silkscreen")
		(7 "B.SilkS" user "B.Silkscreen")
		(1 "F.Mask" user)
		(3 "B.Mask" user)
		(17 "Dwgs.User" user "User.Drawings")
		(19 "Cmts.User" user "User.Comments")
		(21 "Eco1.User" user "User.Eco1")
		(23 "Eco2.User" user "User.Eco2")
		(25 "Edge.Cuts" user)
		(27 "Margin" user)
		(31 "F.CrtYd" user "F.Courtyard")
		(29 "B.CrtYd" user "B.Courtyard")
		(35 "F.Fab" user)
		(33 "B.Fab" user)
	)
	(footprint "antmicro-footprints:MLP44-24L_4x4x0.75mm"
		(layer "F.Cu")
		(at 179.7 90.45)
		(property "Reference" "U11"
			(at -2.675532 2.785 90)
			(layer "F.SilkS")
			(effects
				(font
					(size 0.7 0.7)
					(thickness 0.15)
				)
				(justify left bottom)
			)
		)
		(property "Value" "SIC437AED-T1-GE3"
			(at -2.7 3.6 0)
			(layer "F.Fab")
			(effects
				(font
					(size 0.7 0.7)
					(thickness 0.15)
				)
				(justify left bottom)
			)
		)
		(property "Datasheet" "https://www.vishay.com/docs/75921/sic437.pdf"
			(at 0 0 0)
			(layer "F.Fab")
			(hide yes)
			(effects
				(font
					(size 1.27 1.27)
					(thickness 0.15)
				)
			)
		)
		(property "Description" "DC/DC Buck Step Down Regulator Adjustable, 4.5-28V In, 0.6V to 20V/12A Out, 1MHz, PowerPAK MLP44-24"
			(at 0 0 0)
			(layer "F.Fab")
			(hide yes)
			(effects
				(font
					(size 1.27 1.27)
					(thickness 0.15)
				)
			)
		)
		(property "Manufacturer" "Vishay"
			(at 0 0 0)
			(unlocked yes)
			(layer "F.Fab")
			(hide yes)
			(effects
				(font
					(size 1 1)
					(thickness 0.15)
				)
			)
		)
		(property "MPN" "SIC437AED-T1-GE3"
			(at 0 0 0)
			(unlocked yes)
			(layer "F.Fab")
			(hide yes)
			(effects
				(font
					(size 1 1)
					(thickness 0.15)
				)
			)
		)
		(property "Author" "Antmicro"
			(at 0 0 0)
			(unlocked yes)
			(layer "F.Fab")
			(hide yes)
			(effects
				(font
					(size 1 1)
					(thickness 0.15)
				)
			)
		)
		(property "License" "Apache-2.0"
			(at 0 0 0)
			(unlocked yes)
			(layer "F.Fab")
			(hide yes)
			(effects
				(font
					(size 1 1)
					(thickness 0.15)
				)
			)
		)
		(component_classes
			(class "DCDC_SOM")
		)
		(sheetname "/DCDC/")
		(sheetfile "dcdc.kicad_sch")
		(attr smd)
		(net_tie_pad_groups "1,2,26" "3,4,27" "5,6,7,8,9")
		(fp_line
			(start -2.11 -1.38)
			(end -2.11 -2.1)
			(stroke
				(width 0.15)
				(type solid)
			)
			(layer "F.SilkS")
		)
		(fp_line
			(start -2.11 2.11)
			(end -2.11 1.39)
			(stroke
				(width 0.15)
				(type solid)
			)
			(layer "F.SilkS")
		)
		(fp_line
			(start -1.89 -2.1)
			(end -2.11 -2.1)
			(stroke
				(width 0.15)
				(type solid)
			)
			(layer "F.SilkS")
		)
		(fp_line
			(start -1.89 2.11)
			(end -2.11 2.11)
			(stroke
				(width 0.15)
				(type solid)
			)
			(layer "F.SilkS")
		)
		(fp_line
			(start 1.44 2.11)
			(end 2.11 2.11)
			(stroke
				(width 0.15)
				(type solid)
			)
			(layer "F.SilkS")
		)
		(fp_line
			(start 1.89 -2.11)
			(end 2.11 -2.11)
			(stroke
				(width 0.15)
				(type solid)
			)
			(layer "F.SilkS")
		)
		(fp_line
			(start 2.11 -2.11)
			(end 2.11 -1.69)
			(stroke
				(width 0.15)
				(type solid)
			)
			(layer "F.SilkS")
		)
		(fp_line
			(start 2.11 2.11)
			(end 2.11 1.84)
			(stroke
				(width 0.15)
				(type solid)
			)
			(layer "F.SilkS")
		)
		(fp_circle
			(center -2.25 -1.15)
			(end -2.2 -1.15)
			(stroke
				(width 0.15)
				(type solid)
			)
			(fill yes)
			(layer "F.SilkS")
		)
		(fp_line
			(start -2.55 -2.55)
			(end 2.55 -2.55)
			(stroke
				(width 0.05)
				(type solid)
			)
			(layer "F.CrtYd")
		)
		(fp_line
			(start -2.55 2.55)
			(end -2.55 -2.55)
			(stroke
				(width 0.05)
				(type solid)
			)
			(layer "F.CrtYd")
		)
		(fp_line
			(start 2.55 -2.55)
			(end 2.55 2.55)
			(stroke
				(width 0.05)
				(type solid)
			)
			(layer "F.CrtYd")
		)
		(fp_line
			(start 2.55 2.55)
			(end -2.55 2.55)
			(stroke
				(width 0.05)
				(type solid)
			)
			(layer "F.CrtYd")
		)
		(fp_line
			(start -2 -1)
			(end -2 2)
			(stroke
				(width 0.15)
				(type solid)
			)
			(layer "F.Fab")
		)
		(fp_line
			(start -2 2)
			(end 2 2)
			(stroke
				(width 0.15)
				(type solid)
			)
			(layer "F.Fab")
		)
		(fp_line
			(start -1 -2)
			(end -2 -1)
			(stroke
				(width 0.15)
				(type solid)
			)
			(layer "F.Fab")
		)
		(fp_line
			(start 2 -2)
			(end -1 -2)
			(stroke
				(width 0.15)
				(type solid)
			)
			(layer "F.Fab")
		)
		(fp_line
			(start 2 2)
			(end 2 -2)
			(stroke
				(width 0.15)
				(type solid)
			)
			(layer "F.Fab")
		)
		(fp_text user "License: Apache-2.0"
			(at -2.7 5.6 0)
			(layer "F.Fab")
			(effects
				(font
					(size 0.7 0.7)
					(thickness 0.15)
				)
				(justify left bottom)
			)
		)
		(fp_text user "Author: Antmicro"
			(at -2.7 8 0)
			(layer "F.Fab")
			(effects
				(font
					(size 0.7 0.7)
					(thickness 0.15)
				)
				(justify left bottom)
			)
		)
		(fp_text user "${REFERENCE}"
			(at -2.7 6.8 0)
			(layer "F.Fab")
			(effects
				(font
					(size 0.7 0.7)
					(thickness 0.15)
				)
				(justify left bottom)
			)
		)
		(pad "1" smd roundrect
			(at -1.94 -0.825 90)
			(size 0.3 0.725)
			(layers "F.Cu" "F.Mask" "F.Paste")
			(roundrect_rratio 0.25)
			(net 13 "VCC")
			(pinfunction "V_{IN}")
			(pintype "power_in")
		)
		(pad "2" smd roundrect
			(at -1.94 -0.375 90)
			(size 0.3 0.725)
			(layers "F.Cu" "F.Mask" "F.Paste")
			(roundrect_rratio 0.25)
			(net 13 "VCC")
			(pinfunction "V_{IN}")
			(pintype "passive")
		)
		(pad "3" smd roundrect
			(at -1.94 0.525 90)
			(size 0.3 0.725)
			(layers "F.Cu" "F.Mask" "F.Paste")
			(roundrect_rratio 0.25)
			(net 1 "GND")
			(pinfunction "P_{GND}")
			(pintype "passive")
		)
		(pad "4" smd roundrect
			(at -1.94 0.975 90)
			(size 0.3 0.725)
			(layers "F.Cu" "F.Mask" "F.Paste")
			(roundrect_rratio 0.25)
			(net 1 "GND")
			(pinfunction "P_{GND}")
			(pintype "passive")
		)
		(pad "5" smd custom
			(at -1.475 1.94)
			(size 0.3 0.3)
			(layers "F.Cu" "F.Mask" "F.Paste")
			(net 1183 "/DCDC/16V_SW")
			(pinfunction "SW")
			(pintype "passive")
			(options
				(clearance outline)
				(anchor circle)
			)
			(primitives
				(gr_poly
					(pts
						(xy -0.15 -0.2875) (xy -0.144291 -0.316201) (xy -0.128033 -0.340533) (xy -0.103701 -0.356791)
						(xy -0.075 -0.3625) (xy 0.075 -0.3625) (xy 0.103701 -0.356791) (xy 0.128033 -0.340533) (xy 0.144291 -0.316201)
						(xy 0.15 -0.2875) (xy 0.15 0.2875) (xy 0.144291 0.316201) (xy 0.128033 0.340533) (xy 0.103701 0.356791)
						(xy 0.075 0.3625) (xy -0.075 0.3625) (xy -0.103701 0.356791) (xy -0.128033 0.340533) (xy -0.144291 0.316201)
						(xy -0.15 0.2875)
					)
					(width 0)
					(fill yes)
				)
				(gr_poly
					(pts
						(xy -0.15 -0.3625) (xy 2.2 -0.3625) (xy 2.2 -0.0875) (xy -0.15 -0.0875)
					)
					(width 0)
					(fill yes)
				)
			)
		)
		(pad "6" smd roundrect
			(at -1.025 1.94)
			(size 0.3 0.725)
			(layers "F.Cu" "F.Mask" "F.Paste")
			(roundrect_rratio 0.25)
			(net 1183 "/DCDC/16V_SW")
			(pinfunction "SW")
			(pintype "passive")
		)
		(pad "7" smd roundrect
			(at -0.575 1.94)
			(size 0.3 0.725)
			(layers "F.Cu" "F.Mask" "F.Paste")
			(roundrect_rratio 0.25)
			(net 1183 "/DCDC/16V_SW")
			(pinfunction "SW")
			(pintype "passive")
		)
		(pad "8" smd roundrect
			(at 0.125 1.94)
			(size 0.3 0.725)
			(layers "F.Cu" "F.Mask" "F.Paste")
			(roundrect_rratio 0.25)
			(net 1183 "/DCDC/16V_SW")
			(pinfunction "SW")
			(pintype "passive")
		)
		(pad "9" smd roundrect
			(at 0.575 1.94)
			(size 0.3 0.725)
			(layers "F.Cu" "F.Mask" "F.Paste")
			(roundrect_rratio 0.25)
			(net 1183 "/DCDC/16V_SW")
			(pinfunction "SW")
			(pintype "passive")
		)
		(pad "10" smd roundrect
			(at 1.025 1.935)
			(size 0.3 0.725)
			(layers "F.Cu" "F.Mask" "F.Paste")
			(roundrect_rratio 0.25)
			(net 1189 "unconnected-(U11-GL-Pad10)_1")
			(pinfunction "GL")
			(pintype "passive+no_connect")
		)
		(pad "11" smd roundrect
			(at 1.94 1.425 90)
			(size 0.3 0.725)
			(layers "F.Cu" "F.Mask" "F.Paste")
			(roundrect_rratio 0.25)
			(net 1188 "unconnected-(U11-GL-Pad10)")
			(pinfunction "GL")
			(pintype "passive+no_connect")
		)
		(pad "12" smd roundrect
			(at 1.94 0.975 90)
			(size 0.3 0.725)
			(layers "F.Cu" "F.Mask" "F.Paste")
			(roundrect_rratio 0.25)
			(net 900 "/DCDC/16V_VDRV")
			(pinfunction "V_{DRV}")
			(pintype "passive")
		)
		(pad "13" smd roundrect
			(at 1.94 0.525 90)
			(size 0.3 0.725)
			(layers "F.Cu" "F.Mask" "F.Paste")
			(roundrect_rratio 0.25)
			(net 1 "GND")
			(pinfunction "P_{GND}")
			(pintype "power_in")
		)
		(pad "14" smd roundrect
			(at 1.94 0.075 90)
			(size 0.3 0.725)
			(layers "F.Cu" "F.Mask" "F.Paste")
			(roundrect_rratio 0.25)
			(net 246 "/SoM_Power/~{VDDIN_PWR_BAD}")
			(pinfunction "P_{GOOD}")
			(pintype "output")
		)
		(pad "15" smd roundrect
			(at 1.94 -0.375 90)
			(size 0.3 0.725)
			(layers "F.Cu" "F.Mask" "F.Paste")
			(roundrect_rratio 0.25)
			(net 896 "/DCDC/16V_VDD")
			(pinfunction "V_{DD}")
			(pintype "passive")
		)
		(pad "16" smd roundrect
			(at 1.94 -0.825 90)
			(size 0.3 0.725)
			(layers "F.Cu" "F.Mask" "F.Paste")
			(roundrect_rratio 0.25)
			(net 1 "GND")
			(pinfunction "A_{GND}")
			(pintype "power_in")
		)
		(pad "17" smd roundrect
			(at 1.94 -1.275 90)
			(size 0.3 0.725)
			(layers "F.Cu" "F.Mask" "F.Paste")
			(roundrect_rratio 0.25)
			(net 1219 "/DCDC/16V_FB")
			(pinfunction "FB")
			(pintype "passive")
		)
		(pad "18" smd roundrect
			(at 1.475 -1.94)
			(size 0.3 0.725)
			(layers "F.Cu" "F.Mask" "F.Paste")
			(roundrect_rratio 0.25)
			(net 903 "/DCDC/16V_OUT")
			(pinfunction "V_{OUT}")
			(pintype "passive")
		)
		(pad "19" smd roundrect
			(at 1.025 -1.94)
			(size 0.3 0.725)
			(layers "F.Cu" "F.Mask" "F.Paste")
			(roundrect_rratio 0.25)
			(net 1285 "/SoM_Power/VIN_PWR_ON")
			(pinfunction "EN")
			(pintype "input")
		)
		(pad "20" smd roundrect
			(at 0.575 -1.94)
			(size 0.3 0.725)
			(layers "F.Cu" "F.Mask" "F.Paste")
			(roundrect_rratio 0.25)
			(net 1214 "/DCDC/16V_MODE2")
			(pinfunction "MODE2")
			(pintype "input")
		)
		(pad "21" smd roundrect
			(at 0.125 -1.94)
			(size 0.3 0.725)
			(layers "F.Cu" "F.Mask" "F.Paste")
			(roundrect_rratio 0.25)
			(net 1207 "/DCDC/16V_MODE1")
			(pinfunction "MODE1")
			(pintype "input")
		)
		(pad "22" smd roundrect
			(at -0.575 -1.94)
			(size 0.3 0.725)
			(layers "F.Cu" "F.Mask" "F.Paste")
			(roundrect_rratio 0.25)
			(net 13 "VCC")
			(pinfunction "V_{IN}")
			(pintype "passive")
		)
		(pad "23" smd roundrect
			(at -1.025 -1.94)
			(size 0.3 0.725)
			(layers "F.Cu" "F.Mask" "F.Paste")
			(roundrect_rratio 0.25)
			(net 901 "/DCDC/16V_BOOT")
			(pinfunction "BOOT")
			(pintype "passive")
		)
		(pad "24" smd roundrect
			(at -1.475 -1.94)
			(size 0.3 0.725)
			(layers "F.Cu" "F.Mask" "F.Paste")
			(roundrect_rratio 0.25)
			(net 902 "/DCDC/16V_PHASE")
			(pinfunction "PHASE")
			(pintype "passive")
		)
		(pad "25" smd rect
			(at 0.49 -0.75 180)
			(size 1.575 1.05)
			(layers "F.Cu" "F.Mask" "F.Paste")
			(net 1 "GND")
			(pinfunction "A_{GND}")
			(pintype "passive")
		)
		(pad "26" smd rect
			(at -1.175 -0.75 180)
			(size 1.15 1.05)
			(layers "F.Cu" "F.Mask" "F.Paste")
			(net 13 "VCC")
			(pinfunction "V_{IN}")
			(pintype "passive")
		)
		(pad "27" smd custom
			(at -0.75 0.775)
			(size 1 1)
			(layers "F.Cu" "F.Mask" "F.Paste")
			(net 1 "GND")
			(pinfunction "P_{GND}")
			(pintype "passive")
			(options
				(clearance outline)
				(anchor rect)
			)
			(primitives
				(gr_poly
					(pts
						(xy -1 0.5) (xy -1 -0.7) (xy 1.825 -0.7) (xy 1.825 -0.245) (xy 1.175 -0.245) (xy 1.175 0.5)
					)
					(width 0)
					(fill yes)
				)
			)
		)
		(pad "28" smd rect
			(at 0.985 0.99 180)
			(size 0.58 0.38)
			(layers "F.Cu" "F.Mask" "F.Paste")
			(net 1190 "unconnected-(U11-GL-Pad10)_2")
			(pinfunction "GL")
			(pintype "passive+no_connect")
		)
	)
	(footprint "antmicro-footprints:SOT-23-6"
		(layer "F.Cu")
		(at 91 59.5 90)
		(property "Reference" "U70"
			(at 2.45 1.05 0)
			(layer "F.SilkS")
			(effects
				(font
					(size 0.7 0.7)
					(thickness 0.15)
				)
				(justify right top)
			)
		)
		(property "Value" "MAX16150A_SOT"
			(at -1.75 2.693 90)
			(layer "F.Fab")
			(effects
				(font
					(size 0.7 0.7)
					(thickness 0.15)
				)
				(justify left bottom)
			)
		)
		(property "Datasheet" "https://datasheets.maximintegrated.com/en/ds/MAX16150.pdf"
			(at 0 -0.057 90)
			(layer "F.Fab")
			(hide yes)
			(effects
				(font
					(size 1.27 1.27)
					(thickness 0.15)
				)
			)
		)
		(property "Description" "Pushbutton On/Off Controller, Latched Output, 1.3 to 5.5 V Supply, 50 ms Debounce Time, SOT-23-6"
			(at 0 -0.057 90)
			(layer "F.Fab")
			(hide yes)
			(effects
				(font
					(size 1.27 1.27)
					(thickness 0.15)
				)
			)
		)
		(property "Manufacturer" "Maxim Integrated Products"
			(at 0 0 90)
			(unlocked yes)
			(layer "F.Fab")
			(hide yes)
			(effects
				(font
					(size 1 1)
					(thickness 0.15)
				)
			)
		)
		(property "MPN" "MAX16150AUT+T"
			(at 0 0 90)
			(unlocked yes)
			(layer "F.Fab")
			(hide yes)
			(effects
				(font
					(size 1 1)
					(thickness 0.15)
				)
			)
		)
		(property "License" "Apache-2.0"
			(at 0 0 90)
			(unlocked yes)
			(layer "F.Fab")
			(hide yes)
			(effects
				(font
					(size 1 1)
					(thickness 0.15)
				)
			)
		)
		(property "Author" "Antmicro"
			(at 0 0 90)
			(unlocked yes)
			(layer "F.Fab")
			(hide yes)
			(effects
				(font
					(size 1 1)
					(thickness 0.15)
				)
			)
		)
		(sheetname "/SoM_Power/")
		(sheetfile "som_power.kicad_sch")
		(attr smd)
		(fp_line
			(start 1.45 -0.757)
			(end 1.45 -0.457)
			(stroke
				(width 0.12)
				(type solid)
			)
			(layer "F.SilkS")
		)
		(fp_line
			(start 1.3 -0.757)
			(end 1.45 -0.757)
			(stroke
				(width 0.12)
				(type solid)
			)
			(layer "F.SilkS")
		)
		(fp_line
			(start -1.3 -0.757)
			(end -1.45 -0.757)
			(stroke
				(width 0.12)
				(type solid)
			)
			(layer "F.SilkS")
		)
		(fp_line
			(start -1.45 -0.757)
			(end -1.45 -0.457)
			(stroke
				(width 0.12)
				(type solid)
			)
			(layer "F.SilkS")
		)
		(fp_line
			(start 1.45 0.643)
			(end 1.45 0.343)
			(stroke
				(width 0.12)
				(type solid)
			)
			(layer "F.SilkS")
		)
		(fp_line
			(start 1.3 0.643)
			(end 1.45 0.643)
			(stroke
				(width 0.12)
				(type solid)
			)
			(layer "F.SilkS")
		)
		(fp_line
			(start -1.45 0.643)
			(end -1.45 0.343)
			(stroke
				(width 0.12)
				(type solid)
			)
			(layer "F.SilkS")
		)
		(fp_rect
			(start -1.55 -1.85)
			(end 1.55 1.75)
			(stroke
				(width 0.05)
				(type solid)
			)
			(fill no)
			(layer "F.CrtYd")
		)
		(fp_line
			(start 1.5 -0.757)
			(end 1.5 0.643)
			(stroke
				(width 0.1)
				(type solid)
			)
			(layer "F.Fab")
		)
		(fp_line
			(start -1.5 -0.757)
			(end 1.5 -0.757)
			(stroke
				(width 0.1)
				(type solid)
			)
			(layer "F.Fab")
		)
		(fp_line
			(start 1.5 0.643)
			(end -1.5 0.643)
			(stroke
				(width 0.1)
				(type solid)
			)
			(layer "F.Fab")
		)
		(fp_line
			(start -1.5 0.643)
			(end -1.5 -0.757)
			(stroke
				(width 0.1)
				(type solid)
			)
			(layer "F.Fab")
		)
		(fp_text user "."
			(at -1.4 1.143 90)
			(layer "F.SilkS")
			(effects
				(font
					(size 1 1)
					(thickness 0.15)
				)
			)
		)
		(fp_text user "License: Apache-2.0"
			(at -1.75 6.5 90)
			(layer "F.Fab")
			(effects
				(font
					(size 0.7 0.7)
					(thickness 0.15)
				)
				(justify left bottom)
			)
		)
		(fp_text user "Author: Antmicro"
			(at -1.829 5.25 90)
			(layer "F.Fab")
			(effects
				(font
					(size 0.7 0.7)
					(thickness 0.15)
				)
				(justify left bottom)
			)
		)
		(fp_text user "${REFERENCE}"
			(at -1.75 4 90)
			(layer "F.Fab")
			(effects
				(font
					(size 0.7 0.7)
					(thickness 0.15)
				)
				(justify left bottom)
			)
		)
		(pad "1" smd roundrect
			(at -0.954 1.1 90)
			(size 0.55 1)
			(layers "F.Cu" "F.Mask" "F.Paste")
			(roundrect_rratio 0.15)
			(net 610 "/SoM_Power/~{PWR_BTN}")
			(pinfunction "~{PB_IN}")
			(pintype "input")
		)
		(pad "2" smd roundrect
			(at -0.003 1.1 90)
			(size 0.55 1)
			(layers "F.Cu" "F.Mask" "F.Paste")
			(roundrect_rratio 0.15)
			(net 1 "GND")
			(pinfunction "GND")
			(pintype "power_in")
		)
		(pad "3" smd roundrect
			(at 0.947 1.1 90)
			(size 0.55 1)
			(layers "F.Cu" "F.Mask" "F.Paste")
			(roundrect_rratio 0.15)
			(net 491 "+5V_AON")
			(pinfunction "VCC")
			(pintype "power_in")
		)
		(pad "4" smd roundrect
			(at 0.947 -1.214 90)
			(size 0.55 1)
			(layers "F.Cu" "F.Mask" "F.Paste")
			(roundrect_rratio 0.15)
			(net 1033 "Net-(U70-OUT)")
			(pinfunction "OUT")
			(pintype "output")
		)
		(pad "5" smd roundrect
			(at -0.003 -1.214 90)
			(size 0.55 1)
			(layers "F.Cu" "F.Mask" "F.Paste")
			(roundrect_rratio 0.15)
			(net 1035 "Net-(U70-~{INT})")
			(pinfunction "~{INT}")
			(pintype "output")
		)
		(pad "6" smd roundrect
			(at -0.954 -1.214 90)
			(size 0.55 1)
			(layers "F.Cu" "F.Mask" "F.Paste")
			(roundrect_rratio 0.15)
			(net 1027 "Net-(U70-~{CLR})")
			(pinfunction "~{CLR}")
			(pintype "input")
		)
	)
)
